# S9S_MB_2U (Grand Teton) — schematic netlist excerpt (pin names and nets, part order shuffled) for the footprints in the layout excerpt that follows; sources: Cadence DE-HDL packaged netlist, KiCad conversion of 03242023_DA0F0TMBIJ0_F0T_Motherboard_J_brd_V01_OCP.brd

PC1253  Q_CAP  680PF 50V 10% X7R  pkg C0402  page 281 : A = PVPP_HBM_CPU0_FB ; B = SH_PVPP_HBM_CPU0_P
PC562_P1_2  Q_CAP  1UF 16V 10% X6S  pkg C0402  page 285 : A = SW_P12V_PVCCIN_CPU1_FLT ; B = GND

(kicad_pcb
	(version 20260206)
	(generator "pcbnew")
	(generator_version "10.0")
	(general
		(thickness 1.6)
		(legacy_teardrops no)
	)
	(paper "A4")
	(title_block
		(title "03242023_DA0F0TMBIJ0_F0T_Motherboard_J_brd_V01_OCP.brd")
		(comment 1 "Grand Teton / footprints 2186-2187 of 6105")
	)
	(layers
		(0 "F.Cu" signal "TOP")
		(4 "In1.Cu" signal "GND")
		(6 "In2.Cu" signal "IN1")
		(8 "In3.Cu" signal "GND1")
		(10 "In4.Cu" signal "IN2")
		(12 "In5.Cu" signal "GND2")
		(14 "In6.Cu" signal "IN3")
		(16 "In7.Cu" signal "GND3")
		(18 "In8.Cu" signal "VCC")
		(20 "In9.Cu" signal "VCC1")
		(22 "In10.Cu" signal "GND4")
		(24 "In11.Cu" signal "IN4")
		(26 "In12.Cu" signal "GND5")
		(28 "In13.Cu" signal "IN5")
		(30 "In14.Cu" signal "GND6")
		(32 "In15.Cu" signal "IN6")
		(34 "In16.Cu" signal "GND7")
		(2 "B.Cu" signal "BOTTOM")
		(9 "F.Adhes" user "F.Adhesive")
		(11 "B.Adhes" user "B.Adhesive")
		(13 "F.Paste" user "Package Geometry/Pastemask Top")
		(15 "B.Paste" user "Package Geometry/Pastemask Bottom")
		(5 "F.SilkS" user "Ref Des/Silkscreen Top")
		(7 "B.SilkS" user "Ref Des/Silkscreen Bottom")
		(1 "F.Mask" user "Board Geometry/Soldermask Top")
		(3 "B.Mask" user "Board Geometry/Soldermask Bottom")
		(17 "Dwgs.User" user "User.Drawings")
		(19 "Cmts.User" user "User.Comments")
		(21 "Eco1.User" user "User.Eco1")
		(23 "Eco2.User" user "User.Eco2")
		(25 "Edge.Cuts" user "Board Geometry/Outline")
		(27 "Margin" user)
		(31 "F.CrtYd" user "Package Geometry/Place Bound Top")
		(29 "B.CrtYd" user "Package Geometry/Place Bound Bottom")
		(35 "F.Fab" user "Ref Des/Assembly Top")
		(33 "B.Fab" user "Ref Des/Assembly Bottom")
	)
	(footprint ""
		(layer "F.Cu")
		(at 369.191286 -357.11638 90)
		(property "Reference" "PC1253"
			(at 0 0 90)
			(layer "F.SilkS")
			(hide yes)
			(effects
				(font
					(size 1.27 1.27)
				)
			)
		)
		(property "Value" ""
			(at 0 0 90)
			(layer "F.Fab")
			(effects
				(font
					(size 1.27 1.27)
				)
			)
		)
		(duplicate_pad_numbers_are_jumpers no)
		(fp_line
			(start 0.7874 -0.4064)
			(end 0.7874 0.4064)
			(stroke
				(width 0.1524)
				(type default)
			)
			(layer "F.SilkS")
		)
		(fp_line
			(start -0.7874 -0.4064)
			(end 0.7874 -0.4064)
			(stroke
				(width 0.1524)
				(type default)
			)
			(layer "F.SilkS")
		)
		(fp_line
			(start 0.7874 0.4064)
			(end -0.7874 0.4064)
			(stroke
				(width 0.1524)
				(type default)
			)
			(layer "F.SilkS")
		)
		(fp_line
			(start -0.7874 0.4064)
			(end -0.7874 -0.4064)
			(stroke
				(width 0.1524)
				(type default)
			)
			(layer "F.SilkS")
		)
		(fp_line
			(start -0.12065 -0.305054)
			(end -0.12065 -0.2794)
			(stroke
				(width 0.1)
				(type default)
			)
			(layer "F.Fab")
		)
		(fp_line
			(start -0.67945 -0.305054)
			(end -0.12065 -0.305054)
			(stroke
				(width 0.1)
				(type default)
			)
			(layer "F.Fab")
		)
		(fp_line
			(start 0.67945 -0.3048)
			(end 0.67945 0.3048)
			(stroke
				(width 0.1)
				(type default)
			)
			(layer "F.Fab")
		)
		(fp_line
			(start 0.12065 -0.3048)
			(end 0.67945 -0.3048)
			(stroke
				(width 0.1)
				(type default)
			)
			(layer "F.Fab")
		)
		(fp_line
			(start 0.12065 -0.2794)
			(end 0.12065 -0.3048)
			(stroke
				(width 0.1)
				(type default)
			)
			(layer "F.Fab")
		)
		(fp_line
			(start -0.12065 -0.2794)
			(end 0.12065 -0.2794)
			(stroke
				(width 0.1)
				(type default)
			)
			(layer "F.Fab")
		)
		(fp_line
			(start 0.120396 0.2794)
			(end -0.12065 0.2794)
			(stroke
				(width 0.1)
				(type default)
			)
			(layer "F.Fab")
		)
		(fp_line
			(start -0.12065 0.2794)
			(end -0.12065 0.3048)
			(stroke
				(width 0.1)
				(type default)
			)
			(layer "F.Fab")
		)
		(fp_line
			(start 0.67945 0.3048)
			(end 0.120396 0.3048)
			(stroke
				(width 0.1)
				(type default)
			)
			(layer "F.Fab")
		)
		(fp_line
			(start 0.120396 0.3048)
			(end 0.120396 0.2794)
			(stroke
				(width 0.1)
				(type default)
			)
			(layer "F.Fab")
		)
		(fp_line
			(start -0.12065 0.3048)
			(end -0.67945 0.3048)
			(stroke
				(width 0.1)
				(type default)
			)
			(layer "F.Fab")
		)
		(fp_line
			(start -0.67945 0.3048)
			(end -0.67945 -0.305054)
			(stroke
				(width 0.1)
				(type default)
			)
			(layer "F.Fab")
		)
		(pad "1" smd circle
			(at -0.40005 0 90)
			(size 0 0)
			(layers "F.Cu" "F.Mask" "F.Paste")
			(net "PVPP_HBM_CPU0_FB")
		)
		(pad "2" smd circle
			(at 0.40005 0 90)
			(size 0 0)
			(layers "F.Cu" "F.Mask" "F.Paste")
			(net "SH_PVPP_HBM_CPU0_P")
		)
	)
	(footprint ""
		(layer "F.Cu")
		(at 108.727494 -333.804514 -90)
		(property "Reference" "PC562_P1_2"
			(at 0 0 270)
			(layer "F.SilkS")
			(hide yes)
			(effects
				(font
					(size 1.27 1.27)
				)
			)
		)
		(property "Value" ""
			(at 0 0 270)
			(layer "F.Fab")
			(effects
				(font
					(size 1.27 1.27)
				)
			)
		)
		(duplicate_pad_numbers_are_jumpers no)
		(fp_line
			(start -0.7874 0.4064)
			(end -0.7874 -0.4064)
			(stroke
				(width 0.1524)
				(type default)
			)
			(layer "F.SilkS")
		)
		(fp_line
			(start 0.7874 0.4064)
			(end -0.7874 0.4064)
			(stroke
				(width 0.1524)
				(type default)
			)
			(layer "F.SilkS")
		)
		(fp_line
			(start -0.7874 -0.4064)
			(end 0.7874 -0.4064)
			(stroke
				(width 0.1524)
				(type default)
			)
			(layer "F.SilkS")
		)
		(fp_line
			(start 0.7874 -0.4064)
			(end 0.7874 0.4064)
			(stroke
				(width 0.1524)
				(type default)
			)
			(layer "F.SilkS")
		)
		(fp_line
			(start -0.67945 0.3048)
			(end -0.67945 -0.305054)
			(stroke
				(width 0.1)
				(type default)
			)
			(layer "F.Fab")
		)
		(fp_line
			(start -0.12065 0.3048)
			(end -0.67945 0.3048)
			(stroke
				(width 0.1)
				(type default)
			)
			(layer "F.Fab")
		)
		(fp_line
			(start 0.120396 0.3048)
			(end 0.120396 0.2794)
			(stroke
				(width 0.1)
				(type default)
			)
			(layer "F.Fab")
		)
		(fp_line
			(start 0.67945 0.3048)
			(end 0.120396 0.3048)
			(stroke
				(width 0.1)
				(type default)
			)
			(layer "F.Fab")
		)
		(fp_line
			(start -0.12065 0.2794)
			(end -0.12065 0.3048)
			(stroke
				(width 0.1)
				(type default)
			)
			(layer "F.Fab")
		)
		(fp_line
			(start 0.120396 0.2794)
			(end -0.12065 0.2794)
			(stroke
				(width 0.1)
				(type default)
			)
			(layer "F.Fab")
		)
		(fp_line
			(start -0.12065 -0.2794)
			(end 0.12065 -0.2794)
			(stroke
				(width 0.1)
				(type default)
			)
			(layer "F.Fab")
		)
		(fp_line
			(start 0.12065 -0.2794)
			(end 0.12065 -0.3048)
			(stroke
				(width 0.1)
				(type default)
			)
			(layer "F.Fab")
		)
		(fp_line
			(start 0.12065 -0.3048)
			(end 0.67945 -0.3048)
			(stroke
				(width 0.1)
				(type default)
			)
			(layer "F.Fab")
		)
		(fp_line
			(start 0.67945 -0.3048)
			(end 0.67945 0.3048)
			(stroke
				(width 0.1)
				(type default)
			)
			(layer "F.Fab")
		)
		(fp_line
			(start -0.67945 -0.305054)
			(end -0.12065 -0.305054)
			(stroke
				(width 0.1)
				(type default)
			)
			(layer "F.Fab")
		)
		(fp_line
			(start -0.12065 -0.305054)
			(end -0.12065 -0.2794)
			(stroke
				(width 0.1)
				(type default)
			)
			(layer "F.Fab")
		)
		(pad "1" smd circle
			(at -0.40005 0 270)
			(size 0 0)
			(layers "F.Cu" "F.Mask" "F.Paste")
			(net "SW_P12V_PVCCIN_CPU1_FLT")
		)
		(pad "2" smd circle
			(at 0.40005 0 270)
			(size 0 0)
			(layers "F.Cu" "F.Mask" "F.Paste")
			(net "GND")
		)
	)
)
